(kicad_pcb
	(version 20260206)
	(generator "pcbnew")
	(generator_version "10.0")
	(general
		(thickness 1.6)
		(legacy_teardrops no)
	)
	(paper "A4")
	(title_block
		(title "03242023_DA0F0TMBIJ0_F0T_Motherboard_J_brd_V01_OCP.brd")
		(comment 1 "Grand Teton / footprints 5931-5935 of 6105")
	)
	(layers
		(0 "F.Cu" signal "TOP")
		(4 "In1.Cu" signal "GND")
		(6 "In2.Cu" signal "IN1")
		(8 "In3.Cu" signal "GND1")
		(10 "In4.Cu" signal "IN2")
		(12 "In5.Cu" signal "GND2")
		(14 "In6.Cu" signal "IN3")
		(16 "In7.Cu" signal "GND3")
		(18 "In8.Cu" signal "VCC")
		(20 "In9.Cu" signal "VCC1")
		(22 "In10.Cu" signal "GND4")
		(24 "In11.Cu" signal "IN4")
		(26 "In12.Cu" signal "GND5")
		(28 "In13.Cu" signal "IN5")
		(30 "In14.Cu" signal "GND6")
		(32 "In15.Cu" signal "IN6")
		(34 "In16.Cu" signal "GND7")
		(2 "B.Cu" signal "BOTTOM")
		(9 "F.Adhes" user "F.Adhesive")
		(11 "B.Adhes" user "B.Adhesive")
		(13 "F.Paste" user "Package Geometry/Pastemask Top")
		(15 "B.Paste" user "Package Geometry/Pastemask Bottom")
		(5 "F.SilkS" user "Ref Des/Silkscreen Top")
		(7 "B.SilkS" user "Ref Des/Silkscreen Bottom")
		(1 "F.Mask" user "Board Geometry/Soldermask Top")
		(3 "B.Mask" user "Board Geometry/Soldermask Bottom")
		(17 "Dwgs.User" user "User.Drawings")
		(19 "Cmts.User" user "User.Comments")
		(21 "Eco1.User" user "User.Eco1")
		(23 "Eco2.User" user "User.Eco2")
		(25 "Edge.Cuts" user "Board Geometry/Outline")
		(27 "Margin" user)
		(31 "F.CrtYd" user "Package Geometry/Place Bound Top")
		(29 "B.CrtYd" user "Package Geometry/Place Bound Bottom")
		(35 "F.Fab" user "Ref Des/Assembly Top")
		(33 "B.Fab" user "Ref Des/Assembly Bottom")
	)
	(footprint ""
		(layer "B.Cu")
		(at 339.298534 -2.156206 180)
		(property "Reference" "J70"
			(at 4.248404 -1.165606 270)
			(unlocked yes)
			(layer "B.SilkS")
			(effects
				(font
					(size 0.7874 0.5842)
					(thickness 0.1524)
				)
				(justify left mirror)
			)
		)
		(property "Value" ""
			(at 0 0 0)
			(layer "B.Fab")
			(effects
				(font
					(size 1.27 1.27)
				)
				(justify mirror)
			)
		)
		(duplicate_pad_numbers_are_jumpers no)
		(fp_line
			(start 1.2192 2.1082)
			(end 1.2192 -2.1082)
			(stroke
				(width 0.1524)
				(type default)
			)
			(layer "B.SilkS")
		)
		(fp_line
			(start 1.2192 -2.1082)
			(end -1.2192 -2.1082)
			(stroke
				(width 0.1524)
				(type default)
			)
			(layer "B.SilkS")
		)
		(fp_line
			(start -1.2192 2.1082)
			(end 1.2192 2.1082)
			(stroke
				(width 0.1524)
				(type default)
			)
			(layer "B.SilkS")
		)
		(fp_line
			(start -1.2192 -2.1082)
			(end -1.2192 2.1082)
			(stroke
				(width 0.1524)
				(type default)
			)
			(layer "B.SilkS")
		)
		(pad "" np_thru_hole circle
			(at -3.4671 -1.27 90)
			(size 1.0414 1.0414)
			(drill 1.0414)
			(layers "*.Cu" "*.Mask")
			(clearance 0.381)
			(thermal_gap 0.381)
		)
		(pad "" np_thru_hole circle
			(at -3.4671 1.27 90)
			(size 1.0414 1.0414)
			(drill 1.0414)
			(layers "*.Cu" "*.Mask")
			(clearance 0.381)
			(thermal_gap 0.381)
		)
		(pad "" np_thru_hole circle
			(at 2.8829 -1.27 90)
			(size 1.0414 1.0414)
			(drill 1.0414)
			(layers "*.Cu" "*.Mask")
			(clearance 0.381)
			(thermal_gap 0.381)
		)
		(pad "" np_thru_hole circle
			(at 2.8829 1.27 90)
			(size 1.0414 1.0414)
			(drill 1.0414)
			(layers "*.Cu" "*.Mask")
			(clearance 0.381)
			(thermal_gap 0.381)
		)
		(pad "1" smd rect
			(at -0.8255 -0.249936 90)
			(size 0.3048 0.508)
			(layers "B.Cu" "B.Mask" "B.Paste")
			(net "DELTA_L_85_5INCH_BOT_DN")
		)
		(pad "2" smd rect
			(at -0.8255 0.249936 90)
			(size 0.3048 0.508)
			(layers "B.Cu" "B.Mask" "B.Paste")
			(net "DELTA_L_85_5INCH_BOT_DP")
		)
		(pad "3" smd circle
			(at 0 0)
			(size 0 0)
			(layers "B.Cu" "B.Mask" "B.Paste")
			(net "DELTA_L_GND_1")
		)
		(zone
			(layers "F.Cu" "B.Cu" "In1.Cu" "In2.Cu" "In3.Cu" "In4.Cu" "In5.Cu" "In6.Cu"
				"In7.Cu" "In8.Cu" "In9.Cu" "In10.Cu" "In11.Cu" "In12.Cu" "In13.Cu" "In14.Cu"
				"In15.Cu" "In16.Cu"
			)
			(hatch none 0.5)
			(connect_pads
				(clearance 0)
			)
			(min_thickness 0.25)
			(keepout
				(tracks not_allowed)
				(vias allowed)
				(pads allowed)
				(copperpour not_allowed)
				(footprints allowed)
			)
			(placement
				(enabled no)
				(sheetname "")
			)
			(fill
				(thermal_gap 0.5)
				(thermal_bridge_width 0.5)
				(island_removal_mode 0)
			)
			(polygon
				(pts
					(arc
						(start 337.342734 -3.426206)
						(mid 335.488534 -3.426206)
						(end 337.342734 -3.426206)
					)
				)
			)
		)
		(zone
			(layers "F.Cu" "B.Cu" "In1.Cu" "In2.Cu" "In3.Cu" "In4.Cu" "In5.Cu" "In6.Cu"
				"In7.Cu" "In8.Cu" "In9.Cu" "In10.Cu" "In11.Cu" "In12.Cu" "In13.Cu" "In14.Cu"
				"In15.Cu" "In16.Cu"
			)
			(hatch none 0.5)
			(connect_pads
				(clearance 0)
			)
			(min_thickness 0.25)
			(keepout
				(tracks not_allowed)
				(vias allowed)
				(pads allowed)
				(copperpour not_allowed)
				(footprints allowed)
			)
			(placement
				(enabled no)
				(sheetname "")
			)
			(fill
				(thermal_gap 0.5)
				(thermal_bridge_width 0.5)
				(island_removal_mode 0)
			)
			(polygon
				(pts
					(arc
						(start 337.342734 -0.886206)
						(mid 335.488534 -0.886206)
						(end 337.342734 -0.886206)
					)
				)
			)
		)
		(zone
			(layers "F.Cu" "B.Cu" "In1.Cu" "In2.Cu" "In3.Cu" "In4.Cu" "In5.Cu" "In6.Cu"
				"In7.Cu" "In8.Cu" "In9.Cu" "In10.Cu" "In11.Cu" "In12.Cu" "In13.Cu" "In14.Cu"
				"In15.Cu" "In16.Cu"
			)
			(hatch none 0.5)
			(connect_pads
				(clearance 0)
			)
			(min_thickness 0.25)
			(keepout
				(tracks not_allowed)
				(vias allowed)
				(pads allowed)
				(copperpour not_allowed)
				(footprints allowed)
			)
			(placement
				(enabled no)
				(sheetname "")
			)
			(fill
				(thermal_gap 0.5)
				(thermal_bridge_width 0.5)
				(island_removal_mode 0)
			)
			(polygon
				(pts
					(arc
						(start 343.692734 -3.426206)
						(mid 341.838534 -3.426206)
						(end 343.692734 -3.426206)
					)
				)
			)
		)
		(zone
			(layers "F.Cu" "B.Cu" "In1.Cu" "In2.Cu" "In3.Cu" "In4.Cu" "In5.Cu" "In6.Cu"
				"In7.Cu" "In8.Cu" "In9.Cu" "In10.Cu" "In11.Cu" "In12.Cu" "In13.Cu" "In14.Cu"
				"In15.Cu" "In16.Cu"
			)
			(hatch none 0.5)
			(connect_pads
				(clearance 0)
			)
			(min_thickness 0.25)
			(keepout
				(tracks not_allowed)
				(vias allowed)
				(pads allowed)
				(copperpour not_allowed)
				(footprints allowed)
			)
			(placement
				(enabled no)
				(sheetname "")
			)
			(fill
				(thermal_gap 0.5)
				(thermal_bridge_width 0.5)
				(island_removal_mode 0)
			)
			(polygon
				(pts
					(arc
						(start 343.692734 -0.886206)
						(mid 341.838534 -0.886206)
						(end 343.692734 -0.886206)
					)
				)
			)
		)
		(zone
			(layer "B.Cu")
			(hatch none 0.5)
			(connect_pads
				(clearance 0)
			)
			(min_thickness 0.25)
			(keepout
				(tracks not_allowed)
				(vias allowed)
				(pads allowed)
				(copperpour not_allowed)
				(footprints allowed)
			)
			(placement
				(enabled no)
				(sheetname "")
			)
			(fill
				(thermal_gap 0.5)
				(thermal_bridge_width 0.5)
				(island_removal_mode 0)
			)
			(polygon
				(pts
					(xy 340.416134 -1.607566) (xy 340.416134 -1.70307) (xy 339.819234 -1.70307) (xy 339.819234 -2.10947)
					(xy 340.416134 -2.10947) (xy 340.416134 -2.202942) (xy 339.819234 -2.202942) (xy 339.819234 -2.609342)
					(xy 340.416134 -2.609342) (xy 340.416134 -2.704846) (xy 339.717634 -2.704846) (xy 339.717634 -1.607566)
				)
			)
		)
	)
	(footprint ""
		(layer "B.Cu")
		(at 214.43188 -55.971948)
		(property "Reference" "R3764"
			(at 0 0 0)
			(layer "B.SilkS")
			(hide yes)
			(effects
				(font
					(size 1.27 1.27)
				)
				(justify mirror)
			)
		)
		(property "Value" ""
			(at 0 0 0)
			(layer "B.Fab")
			(effects
				(font
					(size 1.27 1.27)
				)
				(justify mirror)
			)
		)
		(duplicate_pad_numbers_are_jumpers no)
		(fp_line
			(start -0.7874 -0.4064)
			(end -0.7874 0.4064)
			(stroke
				(width 0.1524)
				(type default)
			)
			(layer "B.SilkS")
		)
		(fp_line
			(start -0.7874 0.4064)
			(end 0.7874 0.4064)
			(stroke
				(width 0.1524)
				(type default)
			)
			(layer "B.SilkS")
		)
		(fp_line
			(start 0.7874 -0.4064)
			(end -0.7874 -0.4064)
			(stroke
				(width 0.1524)
				(type default)
			)
			(layer "B.SilkS")
		)
		(fp_line
			(start 0.7874 0.4064)
			(end 0.7874 -0.4064)
			(stroke
				(width 0.1524)
				(type default)
			)
			(layer "B.SilkS")
		)
		(fp_line
			(start -0.67945 -0.3048)
			(end -0.67945 0.3048)
			(stroke
				(width 0.1)
				(type default)
			)
			(layer "B.Fab")
		)
		(fp_line
			(start -0.67945 0.3048)
			(end -0.120396 0.3048)
			(stroke
				(width 0.1)
				(type default)
			)
			(layer "B.Fab")
		)
		(fp_line
			(start -0.12065 -0.3048)
			(end -0.67945 -0.3048)
			(stroke
				(width 0.1)
				(type default)
			)
			(layer "B.Fab")
		)
		(fp_line
			(start -0.12065 -0.2794)
			(end -0.12065 -0.3048)
			(stroke
				(width 0.1)
				(type default)
			)
			(layer "B.Fab")
		)
		(fp_line
			(start -0.120396 0.2794)
			(end 0.12065 0.2794)
			(stroke
				(width 0.1)
				(type default)
			)
			(layer "B.Fab")
		)
		(fp_line
			(start -0.120396 0.3048)
			(end -0.120396 0.2794)
			(stroke
				(width 0.1)
				(type default)
			)
			(layer "B.Fab")
		)
		(fp_line
			(start 0.12065 -0.305054)
			(end 0.12065 -0.2794)
			(stroke
				(width 0.1)
				(type default)
			)
			(layer "B.Fab")
		)
		(fp_line
			(start 0.12065 -0.2794)
			(end -0.12065 -0.2794)
			(stroke
				(width 0.1)
				(type default)
			)
			(layer "B.Fab")
		)
		(fp_line
			(start 0.12065 0.2794)
			(end 0.12065 0.3048)
			(stroke
				(width 0.1)
				(type default)
			)
			(layer "B.Fab")
		)
		(fp_line
			(start 0.12065 0.3048)
			(end 0.67945 0.3048)
			(stroke
				(width 0.1)
				(type default)
			)
			(layer "B.Fab")
		)
		(fp_line
			(start 0.67945 -0.305054)
			(end 0.12065 -0.305054)
			(stroke
				(width 0.1)
				(type default)
			)
			(layer "B.Fab")
		)
		(fp_line
			(start 0.67945 0.3048)
			(end 0.67945 -0.305054)
			(stroke
				(width 0.1)
				(type default)
			)
			(layer "B.Fab")
		)
		(pad "1" smd circle
			(at 0.40005 0 180)
			(size 0 0)
			(layers "B.Cu" "B.Mask" "B.Paste")
			(net "GND")
		)
		(pad "2" smd circle
			(at -0.40005 0 180)
			(size 0 0)
			(layers "B.Cu" "B.Mask" "B.Paste")
			(net "INA230_2_A0")
		)
	)
	(footprint ""
		(layer "B.Cu")
		(at 117.0432 -96.916748 -90)
		(property "Reference" "R4621"
			(at 0 0 90)
			(layer "B.SilkS")
			(hide yes)
			(effects
				(font
					(size 1.27 1.27)
				)
				(justify mirror)
			)
		)
		(property "Value" ""
			(at 0 0 90)
			(layer "B.Fab")
			(effects
				(font
					(size 1.27 1.27)
				)
				(justify mirror)
			)
		)
		(duplicate_pad_numbers_are_jumpers no)
		(fp_line
			(start -0.7874 0.4064)
			(end 0.7874 0.4064)
			(stroke
				(width 0.1524)
				(type default)
			)
			(layer "B.SilkS")
		)
		(fp_line
			(start 0.7874 0.4064)
			(end 0.7874 -0.4064)
			(stroke
				(width 0.1524)
				(type default)
			)
			(layer "B.SilkS")
		)
		(fp_line
			(start -0.7874 -0.4064)
			(end -0.7874 0.4064)
			(stroke
				(width 0.1524)
				(type default)
			)
			(layer "B.SilkS")
		)
		(fp_line
			(start 0.7874 -0.4064)
			(end -0.7874 -0.4064)
			(stroke
				(width 0.1524)
				(type default)
			)
			(layer "B.SilkS")
		)
		(fp_line
			(start -0.67945 0.3048)
			(end -0.120396 0.3048)
			(stroke
				(width 0.1)
				(type default)
			)
			(layer "B.Fab")
		)
		(fp_line
			(start -0.120396 0.3048)
			(end -0.120396 0.2794)
			(stroke
				(width 0.1)
				(type default)
			)
			(layer "B.Fab")
		)
		(fp_line
			(start 0.12065 0.3048)
			(end 0.67945 0.3048)
			(stroke
				(width 0.1)
				(type default)
			)
			(layer "B.Fab")
		)
		(fp_line
			(start 0.67945 0.3048)
			(end 0.67945 -0.305054)
			(stroke
				(width 0.1)
				(type default)
			)
			(layer "B.Fab")
		)
		(fp_line
			(start -0.120396 0.2794)
			(end 0.12065 0.2794)
			(stroke
				(width 0.1)
				(type default)
			)
			(layer "B.Fab")
		)
		(fp_line
			(start 0.12065 0.2794)
			(end 0.12065 0.3048)
			(stroke
				(width 0.1)
				(type default)
			)
			(layer "B.Fab")
		)
		(fp_line
			(start -0.12065 -0.2794)
			(end -0.12065 -0.3048)
			(stroke
				(width 0.1)
				(type default)
			)
			(layer "B.Fab")
		)
		(fp_line
			(start 0.12065 -0.2794)
			(end -0.12065 -0.2794)
			(stroke
				(width 0.1)
				(type default)
			)
			(layer "B.Fab")
		)
		(fp_line
			(start -0.67945 -0.3048)
			(end -0.67945 0.3048)
			(stroke
				(width 0.1)
				(type default)
			)
			(layer "B.Fab")
		)
		(fp_line
			(start -0.12065 -0.3048)
			(end -0.67945 -0.3048)
			(stroke
				(width 0.1)
				(type default)
			)
			(layer "B.Fab")
		)
		(fp_line
			(start 0.12065 -0.305054)
			(end 0.12065 -0.2794)
			(stroke
				(width 0.1)
				(type default)
			)
			(layer "B.Fab")
		)
		(fp_line
			(start 0.67945 -0.305054)
			(end 0.12065 -0.305054)
			(stroke
				(width 0.1)
				(type default)
			)
			(layer "B.Fab")
		)
		(pad "1" smd circle
			(at 0.40005 0 90)
			(size 0 0)
			(layers "B.Cu" "B.Mask" "B.Paste")
			(net "H_CPU_CATERR_LVC2_BMC_R_N")
		)
		(pad "2" smd circle
			(at -0.40005 0 90)
			(size 0 0)
			(layers "B.Cu" "B.Mask" "B.Paste")
			(net "H_CPU_CATERR_LVC2_BMC_N")
		)
	)
	(footprint ""
		(layer "B.Cu")
		(at 201.961496 -194.054984)
		(property "Reference" "R737"
			(at 0 0 0)
			(layer "B.SilkS")
			(hide yes)
			(effects
				(font
					(size 1.27 1.27)
				)
				(justify mirror)
			)
		)
		(property "Value" ""
			(at 0 0 0)
			(layer "B.Fab")
			(effects
				(font
					(size 1.27 1.27)
				)
				(justify mirror)
			)
		)
		(duplicate_pad_numbers_are_jumpers no)
		(fp_line
			(start -0.7874 -0.4064)
			(end -0.7874 0.4064)
			(stroke
				(width 0.1524)
				(type default)
			)
			(layer "B.SilkS")
		)
		(fp_line
			(start -0.7874 0.4064)
			(end 0.7874 0.4064)
			(stroke
				(width 0.1524)
				(type default)
			)
			(layer "B.SilkS")
		)
		(fp_line
			(start 0.7874 -0.4064)
			(end -0.7874 -0.4064)
			(stroke
				(width 0.1524)
				(type default)
			)
			(layer "B.SilkS")
		)
		(fp_line
			(start 0.7874 0.4064)
			(end 0.7874 -0.4064)
			(stroke
				(width 0.1524)
				(type default)
			)
			(layer "B.SilkS")
		)
		(fp_line
			(start -0.67945 -0.3048)
			(end -0.67945 0.3048)
			(stroke
				(width 0.1)
				(type default)
			)
			(layer "B.Fab")
		)
		(fp_line
			(start -0.67945 0.3048)
			(end -0.120396 0.3048)
			(stroke
				(width 0.1)
				(type default)
			)
			(layer "B.Fab")
		)
		(fp_line
			(start -0.12065 -0.3048)
			(end -0.67945 -0.3048)
			(stroke
				(width 0.1)
				(type default)
			)
			(layer "B.Fab")
		)
		(fp_line
			(start -0.12065 -0.2794)
			(end -0.12065 -0.3048)
			(stroke
				(width 0.1)
				(type default)
			)
			(layer "B.Fab")
		)
		(fp_line
			(start -0.120396 0.2794)
			(end 0.12065 0.2794)
			(stroke
				(width 0.1)
				(type default)
			)
			(layer "B.Fab")
		)
		(fp_line
			(start -0.120396 0.3048)
			(end -0.120396 0.2794)
			(stroke
				(width 0.1)
				(type default)
			)
			(layer "B.Fab")
		)
		(fp_line
			(start 0.12065 -0.305054)
			(end 0.12065 -0.2794)
			(stroke
				(width 0.1)
				(type default)
			)
			(layer "B.Fab")
		)
		(fp_line
			(start 0.12065 -0.2794)
			(end -0.12065 -0.2794)
			(stroke
				(width 0.1)
				(type default)
			)
			(layer "B.Fab")
		)
		(fp_line
			(start 0.12065 0.2794)
			(end 0.12065 0.3048)
			(stroke
				(width 0.1)
				(type default)
			)
			(layer "B.Fab")
		)
		(fp_line
			(start 0.12065 0.3048)
			(end 0.67945 0.3048)
			(stroke
				(width 0.1)
				(type default)
			)
			(layer "B.Fab")
		)
		(fp_line
			(start 0.67945 -0.305054)
			(end 0.12065 -0.305054)
			(stroke
				(width 0.1)
				(type default)
			)
			(layer "B.Fab")
		)
		(fp_line
			(start 0.67945 0.3048)
			(end 0.67945 -0.305054)
			(stroke
				(width 0.1)
				(type default)
			)
			(layer "B.Fab")
		)
		(pad "1" smd circle
			(at 0.40005 0 180)
			(size 0 0)
			(layers "B.Cu" "B.Mask" "B.Paste")
			(net "FM_CPU1_SKTOCC_LVT3_N")
		)
		(pad "2" smd circle
			(at -0.40005 0 180)
			(size 0 0)
			(layers "B.Cu" "B.Mask" "B.Paste")
			(net "FM_CPU1_SKTOCC_N")
		)
	)
	(footprint ""
		(layer "B.Cu")
		(at 419.91788 -156.632148 -90)
		(property "Reference" "PR97"
			(at 0 0 90)
			(layer "B.SilkS")
			(hide yes)
			(effects
				(font
					(size 1.27 1.27)
				)
				(justify mirror)
			)
		)
		(property "Value" ""
			(at 0 0 90)
			(layer "B.Fab")
			(effects
				(font
					(size 1.27 1.27)
				)
				(justify mirror)
			)
		)
		(duplicate_pad_numbers_are_jumpers no)
		(fp_line
			(start -0.7874 0.4064)
			(end 0.7874 0.4064)
			(stroke
				(width 0.1524)
				(type default)
			)
			(layer "B.SilkS")
		)
		(fp_line
			(start 0.7874 0.4064)
			(end 0.7874 -0.4064)
			(stroke
				(width 0.1524)
				(type default)
			)
			(layer "B.SilkS")
		)
		(fp_line
			(start -0.7874 -0.4064)
			(end -0.7874 0.4064)
			(stroke
				(width 0.1524)
				(type default)
			)
			(layer "B.SilkS")
		)
		(fp_line
			(start 0.7874 -0.4064)
			(end -0.7874 -0.4064)
			(stroke
				(width 0.1524)
				(type default)
			)
			(layer "B.SilkS")
		)
		(fp_line
			(start -0.67945 0.3048)
			(end -0.120396 0.3048)
			(stroke
				(width 0.1)
				(type default)
			)
			(layer "B.Fab")
		)
		(fp_line
			(start -0.120396 0.3048)
			(end -0.120396 0.2794)
			(stroke
				(width 0.1)
				(type default)
			)
			(layer "B.Fab")
		)
		(fp_line
			(start 0.12065 0.3048)
			(end 0.67945 0.3048)
			(stroke
				(width 0.1)
				(type default)
			)
			(layer "B.Fab")
		)
		(fp_line
			(start 0.67945 0.3048)
			(end 0.67945 -0.305054)
			(stroke
				(width 0.1)
				(type default)
			)
			(layer "B.Fab")
		)
		(fp_line
			(start -0.120396 0.2794)
			(end 0.12065 0.2794)
			(stroke
				(width 0.1)
				(type default)
			)
			(layer "B.Fab")
		)
		(fp_line
			(start 0.12065 0.2794)
			(end 0.12065 0.3048)
			(stroke
				(width 0.1)
				(type default)
			)
			(layer "B.Fab")
		)
		(fp_line
			(start -0.12065 -0.2794)
			(end -0.12065 -0.3048)
			(stroke
				(width 0.1)
				(type default)
			)
			(layer "B.Fab")
		)
		(fp_line
			(start 0.12065 -0.2794)
			(end -0.12065 -0.2794)
			(stroke
				(width 0.1)
				(type default)
			)
			(layer "B.Fab")
		)
		(fp_line
			(start -0.67945 -0.3048)
			(end -0.67945 0.3048)
			(stroke
				(width 0.1)
				(type default)
			)
			(layer "B.Fab")
		)
		(fp_line
			(start -0.12065 -0.3048)
			(end -0.67945 -0.3048)
			(stroke
				(width 0.1)
				(type default)
			)
			(layer "B.Fab")
		)
		(fp_line
			(start 0.12065 -0.305054)
			(end 0.12065 -0.2794)
			(stroke
				(width 0.1)
				(type default)
			)
			(layer "B.Fab")
		)
		(fp_line
			(start 0.67945 -0.305054)
			(end 0.12065 -0.305054)
			(stroke
				(width 0.1)
				(type default)
			)
			(layer "B.Fab")
		)
		(pad "1" smd circle
			(at 0.40005 0 90)
			(size 0 0)
			(layers "B.Cu" "B.Mask" "B.Paste")
			(net "PVCCFA_EHV_CPU0_PVCC")
		)
		(pad "2" smd circle
			(at -0.40005 0 90)
			(size 0 0)
			(layers "B.Cu" "B.Mask" "B.Paste")
			(net "PVCCFA_EHV_CPU0_VDD1")
		)
	)
)
